(kicad_pcb
	(version 20241229)
	(generator "pcbnew")
	(generator_version "9.0")
	(general
		(thickness 1.61)
		(legacy_teardrops no)
	)
	(paper "A3")
	(title_block
		(title "RDIMM DDR5 Tester")
		(date "2026-05-21")
		(rev "2.2.0")
		(company "Antmicro")
		(comment 9 "footprints 745-749 of 796")
	)
	(layers
		(0 "F.Cu" signal)
		(4 "In1.Cu" power)
		(6 "In2.Cu" mixed)
		(8 "In3.Cu" power)
		(10 "In4.Cu" mixed)
		(12 "In5.Cu" power)
		(14 "In6.Cu" mixed)
		(16 "In7.Cu" power)
		(18 "In8.Cu" power)
		(20 "In9.Cu" mixed)
		(22 "In10.Cu" power)
		(2 "B.Cu" signal)
		(9 "F.Adhes" user "F.Adhesive")
		(11 "B.Adhes" user "B.Adhesive")
		(13 "F.Paste" user)
		(15 "B.Paste" user)
		(5 "F.SilkS" user "F.Silkscreen")
		(7 "B.SilkS" user "B.Silkscreen")
		(1 "F.Mask" user)
		(3 "B.Mask" user)
		(17 "Dwgs.User" user "User.Drawings")
		(19 "Cmts.User" user "User.Comments")
		(21 "Eco1.User" user "User.Eco1")
		(23 "Eco2.User" user "User.Eco2")
		(25 "Edge.Cuts" user)
		(27 "Margin" user)
		(31 "F.CrtYd" user "F.Courtyard")
		(29 "B.CrtYd" user "B.Courtyard")
		(35 "F.Fab" user)
		(33 "B.Fab" user)
	)
	(footprint "antmicro-footprints:C_0402_1005Metric_EIA"
		(layer "B.Cu")
		(at 182 162.5 90)
		(descr "Capacitor SMD 0402 (1005 Metric), square (rectangular) end terminal, IPC_7351 nominal, (Body size source: IPC-SM-782 page 76, https://www.pcb-3d.com/wordpress/wp-content/uploads/ipc-sm-782a_amendment_1_and_2.pdf)")
		(tags "capacitor 0402")
		(property "Reference" "C80"
			(at -3.3 0.25 90)
			(layer "B.SilkS")
			(effects
				(font
					(size 0.7 0.7)
					(thickness 0.15)
				)
				(justify right bottom mirror)
			)
		)
		(property "Value" "C_100n_0402"
			(at 0 -1.169 90)
			(layer "B.Fab")
			(effects
				(font
					(size 0.7 0.7)
					(thickness 0.15)
				)
				(justify right bottom mirror)
			)
		)
		(property "Datasheet" "https://www.murata.com/products/productdetail?partno=GRM155R61H104KE14%23"
			(at 0 0 90)
			(layer "F.Fab")
			(hide yes)
			(effects
				(font
					(size 1.27 1.27)
					(thickness 0.15)
				)
			)
		)
		(property "MPN" "GRM155R61H104KE14D"
			(at 0 0 90)
			(unlocked yes)
			(layer "B.Fab")
			(hide yes)
			(effects
				(font
					(size 1 1)
					(thickness 0.15)
				)
				(justify mirror)
			)
		)
		(property "Manufacturer" "Murata"
			(at 0 0 90)
			(unlocked yes)
			(layer "B.Fab")
			(hide yes)
			(effects
				(font
					(size 1 1)
					(thickness 0.15)
				)
				(justify mirror)
			)
		)
		(property "License" "Apache-2.0"
			(at 0 0 90)
			(unlocked yes)
			(layer "B.Fab")
			(hide yes)
			(effects
				(font
					(size 1 1)
					(thickness 0.15)
				)
				(justify mirror)
			)
		)
		(property "Author" "Antmicro"
			(at 0 0 90)
			(unlocked yes)
			(layer "B.Fab")
			(hide yes)
			(effects
				(font
					(size 1 1)
					(thickness 0.15)
				)
				(justify mirror)
			)
		)
		(property "Val" "100n"
			(at 0 0 90)
			(unlocked yes)
			(layer "B.Fab")
			(hide yes)
			(effects
				(font
					(size 1 1)
					(thickness 0.15)
				)
				(justify mirror)
			)
		)
		(property "Voltage" "50V"
			(at 0 0 90)
			(unlocked yes)
			(layer "B.Fab")
			(hide yes)
			(effects
				(font
					(size 1 1)
					(thickness 0.15)
				)
				(justify mirror)
			)
		)
		(property "Dielectric" "X5R"
			(at 0 0 90)
			(unlocked yes)
			(layer "B.Fab")
			(hide yes)
			(effects
				(font
					(size 1 1)
					(thickness 0.15)
				)
				(justify mirror)
			)
		)
		(sheetname "/FPGA power/")
		(sheetfile "fpga-power.kicad_sch")
		(attr smd)
		(fp_rect
			(start -0.95 0.45)
			(end 0.95 -0.45)
			(stroke
				(width 0.05)
				(type default)
			)
			(fill no)
			(layer "B.CrtYd")
		)
		(fp_line
			(start 0.498 -0.248)
			(end -0.5 -0.248)
			(stroke
				(width 0.15)
				(type solid)
			)
			(layer "B.Fab")
		)
		(fp_line
			(start -0.5 -0.248)
			(end -0.5 0.25)
			(stroke
				(width 0.15)
				(type solid)
			)
			(layer "B.Fab")
		)
		(fp_line
			(start 0.498 0.25)
			(end 0.498 -0.248)
			(stroke
				(width 0.15)
				(type solid)
			)
			(layer "B.Fab")
		)
		(fp_line
			(start -0.5 0.25)
			(end 0.498 0.25)
			(stroke
				(width 0.15)
				(type solid)
			)
			(layer "B.Fab")
		)
		(fp_text user "License: Apache-2.0"
			(at -0.9656 -4.369 270)
			(layer "B.Fab")
			(effects
				(font
					(size 0.7 0.7)
					(thickness 0.15)
				)
				(justify left bottom mirror)
			)
		)
		(fp_text user "${REFERENCE}"
			(at -0.9656 -3.169 270)
			(layer "B.Fab")
			(effects
				(font
					(size 0.7 0.7)
					(thickness 0.15)
				)
				(justify left bottom mirror)
			)
		)
		(fp_text user "Author: Antmicro"
			(at -0.9656 -5.569 270)
			(layer "B.Fab")
			(effects
				(font
					(size 0.7 0.7)
					(thickness 0.15)
				)
				(justify left bottom mirror)
			)
		)
		(pad "1" smd roundrect
			(at -0.5 0)
			(size 0.6 0.6)
			(layers "B.Cu" "B.Mask" "B.Paste")
			(roundrect_rratio 0.25)
			(net 1 "GND")
			(pintype "passive")
		)
		(pad "2" smd roundrect
			(at 0.498 0 90)
			(size 0.6 0.6)
			(layers "B.Cu" "B.Mask" "B.Paste")
			(roundrect_rratio 0.25)
			(net 172 "+1V2_MGTAVTT")
			(pintype "passive")
		)
	)
	(footprint "antmicro-footprints:SC70-3"
		(layer "B.Cu")
		(at 114.755 110.25 180)
		(property "Reference" "Q6"
			(at -3.355 -0.334 0)
			(layer "B.SilkS")
			(effects
				(font
					(size 0.7 0.7)
					(thickness 0.15)
				)
				(justify left bottom mirror)
			)
		)
		(property "Value" "BSS138PW"
			(at 0 -2.3 0)
			(layer "B.Fab")
			(effects
				(font
					(size 0.7 0.7)
					(thickness 0.15)
				)
				(justify left bottom mirror)
			)
		)
		(property "Datasheet" "https://assets.nexperia.com/documents/data-sheet/BSS138PW.pdf"
			(at 0 0 180)
			(layer "F.Fab")
			(hide yes)
			(effects
				(font
					(size 1.27 1.27)
					(thickness 0.15)
				)
			)
		)
		(property "MPN" "BSS138PW"
			(at 0 0 180)
			(unlocked yes)
			(layer "B.Fab")
			(hide yes)
			(effects
				(font
					(size 1 1)
					(thickness 0.15)
				)
				(justify mirror)
			)
		)
		(property "Manufacturer" "Nexperia"
			(at 0 0 180)
			(unlocked yes)
			(layer "B.Fab")
			(hide yes)
			(effects
				(font
					(size 1 1)
					(thickness 0.15)
				)
				(justify mirror)
			)
		)
		(property "Author" "Antmicro"
			(at 0 0 180)
			(unlocked yes)
			(layer "B.Fab")
			(hide yes)
			(effects
				(font
					(size 1 1)
					(thickness 0.15)
				)
				(justify mirror)
			)
		)
		(property "License" "Apache-2.0"
			(at 0 0 180)
			(unlocked yes)
			(layer "B.Fab")
			(hide yes)
			(effects
				(font
					(size 1 1)
					(thickness 0.15)
				)
				(justify mirror)
			)
		)
		(sheetname "/FPGA banks HD/")
		(sheetfile "fpga-hd-banks.kicad_sch")
		(attr smd)
		(fp_line
			(start 0.627 0.6)
			(end 0.627 0.999)
			(stroke
				(width 0.15)
				(type solid)
			)
			(layer "B.SilkS")
		)
		(fp_line
			(start 0.627 -0.6)
			(end 0.627 -1.001)
			(stroke
				(width 0.15)
				(type solid)
			)
			(layer "B.SilkS")
		)
		(fp_line
			(start -0.3 1)
			(end 0.627 0.999)
			(stroke
				(width 0.15)
				(type solid)
			)
			(layer "B.SilkS")
		)
		(fp_line
			(start -0.3 -1)
			(end 0.627 -1.001)
			(stroke
				(width 0.15)
				(type solid)
			)
			(layer "B.SilkS")
		)
		(fp_line
			(start 1.4 0.4)
			(end 1.4 -0.4)
			(stroke
				(width 0.05)
				(type solid)
			)
			(layer "B.CrtYd")
		)
		(fp_line
			(start 1.4 -0.4)
			(end 0.9 -0.4)
			(stroke
				(width 0.05)
				(type solid)
			)
			(layer "B.CrtYd")
		)
		(fp_line
			(start 0.9 1.3)
			(end 0.9 0.4)
			(stroke
				(width 0.05)
				(type solid)
			)
			(layer "B.CrtYd")
		)
		(fp_line
			(start 0.9 0.4)
			(end 1.4 0.4)
			(stroke
				(width 0.05)
				(type solid)
			)
			(layer "B.CrtYd")
		)
		(fp_line
			(start 0.9 -0.4)
			(end 0.9 -1.3)
			(stroke
				(width 0.05)
				(type solid)
			)
			(layer "B.CrtYd")
		)
		(fp_line
			(start 0.9 -1.3)
			(end -0.9 -1.3)
			(stroke
				(width 0.05)
				(type solid)
			)
			(layer "B.CrtYd")
		)
		(fp_line
			(start -0.9 1.3)
			(end 0.9 1.3)
			(stroke
				(width 0.05)
				(type solid)
			)
			(layer "B.CrtYd")
		)
		(fp_line
			(start -0.9 1.3)
			(end -0.9 1)
			(stroke
				(width 0.05)
				(type solid)
			)
			(layer "B.CrtYd")
		)
		(fp_line
			(start -0.9 1)
			(end -1.4 1)
			(stroke
				(width 0.05)
				(type solid)
			)
			(layer "B.CrtYd")
		)
		(fp_line
			(start -0.9 -1)
			(end -1.4 -1)
			(stroke
				(width 0.05)
				(type solid)
			)
			(layer "B.CrtYd")
		)
		(fp_line
			(start -0.9 -1.3)
			(end -0.9 -1)
			(stroke
				(width 0.05)
				(type solid)
			)
			(layer "B.CrtYd")
		)
		(fp_line
			(start -1.4 -1)
			(end -1.4 1)
			(stroke
				(width 0.05)
				(type solid)
			)
			(layer "B.CrtYd")
		)
		(fp_rect
			(start -0.623 0.999)
			(end 0.627 -1.001)
			(stroke
				(width 0.15)
				(type solid)
			)
			(fill no)
			(layer "B.Fab")
		)
		(fp_text user "${REFERENCE}"
			(at -1.45 -4.783 0)
			(layer "B.Fab")
			(effects
				(font
					(size 0.7 0.7)
					(thickness 0.15)
				)
				(justify left bottom mirror)
			)
		)
		(fp_text user "Author: Antmicro"
			(at -1.45 -5.782 0)
			(layer "B.Fab")
			(effects
				(font
					(size 0.7 0.7)
					(thickness 0.15)
				)
				(justify left bottom mirror)
			)
		)
		(fp_text user "License: Apache-2.0"
			(at -1.45 -6.782 0)
			(layer "B.Fab")
			(effects
				(font
					(size 0.7 0.7)
					(thickness 0.15)
				)
				(justify left bottom mirror)
			)
		)
		(pad "1" smd rect
			(at -1.051 0.65 90)
			(size 0.6 0.6)
			(layers "B.Cu" "B.Mask" "B.Paste")
			(net 699 "/FPGA banks HD/USR_LED3")
			(pinfunction "G")
			(pintype "passive")
		)
		(pad "2" smd rect
			(at -1.051 -0.65 90)
			(size 0.6 0.6)
			(layers "B.Cu" "B.Mask" "B.Paste")
			(net 1 "GND")
			(pinfunction "S")
			(pintype "passive")
		)
		(pad "3" smd rect
			(at 1.05 0 90)
			(size 0.6 0.6)
			(layers "B.Cu" "B.Mask" "B.Paste")
			(net 274 "Net-(Q6-D)")
			(pinfunction "D")
			(pintype "passive")
		)
	)
	(footprint "antmicro-footprints:C_0402_1005Metric_EIA"
		(layer "B.Cu")
		(at 186 148.5 90)
		(descr "Capacitor SMD 0402 (1005 Metric), square (rectangular) end terminal, IPC_7351 nominal, (Body size source: IPC-SM-782 page 76, https://www.pcb-3d.com/wordpress/wp-content/uploads/ipc-sm-782a_amendment_1_and_2.pdf)")
		(tags "capacitor 0402")
		(property "Reference" "C19"
			(at 9.525 -30.575 90)
			(layer "B.SilkS")
			(effects
				(font
					(size 0.7 0.7)
					(thickness 0.15)
				)
				(justify right bottom mirror)
			)
		)
		(property "Value" "C_100n_0402"
			(at 0 -1.169 90)
			(layer "B.Fab")
			(effects
				(font
					(size 0.7 0.7)
					(thickness 0.15)
				)
				(justify right bottom mirror)
			)
		)
		(property "Datasheet" "https://www.murata.com/products/productdetail?partno=GRM155R61H104KE14%23"
			(at 0 0 90)
			(layer "F.Fab")
			(hide yes)
			(effects
				(font
					(size 1.27 1.27)
					(thickness 0.15)
				)
			)
		)
		(property "MPN" "GRM155R61H104KE14D"
			(at 0 0 90)
			(unlocked yes)
			(layer "B.Fab")
			(hide yes)
			(effects
				(font
					(size 1 1)
					(thickness 0.15)
				)
				(justify mirror)
			)
		)
		(property "Manufacturer" "Murata"
			(at 0 0 90)
			(unlocked yes)
			(layer "B.Fab")
			(hide yes)
			(effects
				(font
					(size 1 1)
					(thickness 0.15)
				)
				(justify mirror)
			)
		)
		(property "License" "Apache-2.0"
			(at 0 0 90)
			(unlocked yes)
			(layer "B.Fab")
			(hide yes)
			(effects
				(font
					(size 1 1)
					(thickness 0.15)
				)
				(justify mirror)
			)
		)
		(property "Author" "Antmicro"
			(at 0 0 90)
			(unlocked yes)
			(layer "B.Fab")
			(hide yes)
			(effects
				(font
					(size 1 1)
					(thickness 0.15)
				)
				(justify mirror)
			)
		)
		(property "Val" "100n"
			(at 0 0 90)
			(unlocked yes)
			(layer "B.Fab")
			(hide yes)
			(effects
				(font
					(size 1 1)
					(thickness 0.15)
				)
				(justify mirror)
			)
		)
		(property "Voltage" "50V"
			(at 0 0 90)
			(unlocked yes)
			(layer "B.Fab")
			(hide yes)
			(effects
				(font
					(size 1 1)
					(thickness 0.15)
				)
				(justify mirror)
			)
		)
		(property "Dielectric" "X5R"
			(at 0 0 90)
			(unlocked yes)
			(layer "B.Fab")
			(hide yes)
			(effects
				(font
					(size 1 1)
					(thickness 0.15)
				)
				(justify mirror)
			)
		)
		(sheetname "/FPGA power/")
		(sheetfile "fpga-power.kicad_sch")
		(attr smd)
		(fp_rect
			(start -0.95 0.45)
			(end 0.95 -0.45)
			(stroke
				(width 0.05)
				(type default)
			)
			(fill no)
			(layer "B.CrtYd")
		)
		(fp_line
			(start 0.498 -0.248)
			(end -0.5 -0.248)
			(stroke
				(width 0.15)
				(type solid)
			)
			(layer "B.Fab")
		)
		(fp_line
			(start -0.5 -0.248)
			(end -0.5 0.25)
			(stroke
				(width 0.15)
				(type solid)
			)
			(layer "B.Fab")
		)
		(fp_line
			(start 0.498 0.25)
			(end 0.498 -0.248)
			(stroke
				(width 0.15)
				(type solid)
			)
			(layer "B.Fab")
		)
		(fp_line
			(start -0.5 0.25)
			(end 0.498 0.25)
			(stroke
				(width 0.15)
				(type solid)
			)
			(layer "B.Fab")
		)
		(fp_text user "Author: Antmicro"
			(at -0.9656 -5.569 270)
			(layer "B.Fab")
			(effects
				(font
					(size 0.7 0.7)
					(thickness 0.15)
				)
				(justify left bottom mirror)
			)
		)
		(fp_text user "${REFERENCE}"
			(at -0.9656 -3.169 270)
			(layer "B.Fab")
			(effects
				(font
					(size 0.7 0.7)
					(thickness 0.15)
				)
				(justify left bottom mirror)
			)
		)
		(fp_text user "License: Apache-2.0"
			(at -0.9656 -4.369 270)
			(layer "B.Fab")
			(effects
				(font
					(size 0.7 0.7)
					(thickness 0.15)
				)
				(justify left bottom mirror)
			)
		)
		(pad "1" smd roundrect
			(at -0.5 0)
			(size 0.6 0.6)
			(layers "B.Cu" "B.Mask" "B.Paste")
			(roundrect_rratio 0.25)
			(net 1 "GND")
			(pintype "passive")
		)
		(pad "2" smd roundrect
			(at 0.498 0 90)
			(size 0.6 0.6)
			(layers "B.Cu" "B.Mask" "B.Paste")
			(roundrect_rratio 0.25)
			(net 553 "+0V85")
			(pintype "passive")
		)
	)
	(footprint "antmicro-footprints:R_0402_1005Metric"
		(layer "B.Cu")
		(at 238.777999 143.09)
		(descr "Resistor SMD 0402")
		(tags "resistor SMD 0402")
		(property "Reference" "R235"
			(at 1.397001 0.385 0)
			(layer "B.SilkS")
			(effects
				(font
					(size 0.7 0.7)
					(thickness 0.15)
				)
				(justify right bottom mirror)
			)
		)
		(property "Value" "R_47k_0402"
			(at -1.011843 -1.772047 0)
			(layer "B.Fab")
			(effects
				(font
					(size 0.7 0.7)
					(thickness 0.15)
				)
				(justify right bottom mirror)
			)
		)
		(property "Datasheet" "https://www.bourns.com/docs/product-datasheets/cr.pdf"
			(at 0 0 0)
			(layer "F.Fab")
			(hide yes)
			(effects
				(font
					(size 1.27 1.27)
					(thickness 0.15)
				)
			)
		)
		(property "Manufacturer" "Bourns"
			(at 0 0 0)
			(unlocked yes)
			(layer "B.Fab")
			(hide yes)
			(effects
				(font
					(size 1 1)
					(thickness 0.15)
				)
				(justify mirror)
			)
		)
		(property "MPN" "CR0402-FX-4702GLF"
			(at 0 0 0)
			(unlocked yes)
			(layer "B.Fab")
			(hide yes)
			(effects
				(font
					(size 1 1)
					(thickness 0.15)
				)
				(justify mirror)
			)
		)
		(property "Val" "47k"
			(at 0 0 0)
			(unlocked yes)
			(layer "B.Fab")
			(hide yes)
			(effects
				(font
					(size 1 1)
					(thickness 0.15)
				)
				(justify mirror)
			)
		)
		(property "License" "Apache-2.0"
			(at 0 0 0)
			(unlocked yes)
			(layer "B.Fab")
			(hide yes)
			(effects
				(font
					(size 1 1)
					(thickness 0.15)
				)
				(justify mirror)
			)
		)
		(property "Author" "Antmicro"
			(at 0 0 0)
			(unlocked yes)
			(layer "B.Fab")
			(hide yes)
			(effects
				(font
					(size 1 1)
					(thickness 0.15)
				)
				(justify mirror)
			)
		)
		(property "Tolerance" "1%"
			(at 0 0 0)
			(unlocked yes)
			(layer "B.Fab")
			(hide yes)
			(effects
				(font
					(size 1 1)
					(thickness 0.15)
				)
				(justify mirror)
			)
		)
		(sheetname "/Supply/")
		(sheetfile "supply.kicad_sch")
		(attr smd)
		(fp_rect
			(start -0.925 0.47)
			(end 0.925 -0.47)
			(stroke
				(width 0.05)
				(type default)
			)
			(fill no)
			(layer "B.CrtYd")
		)
		(fp_rect
			(start -0.5 0.25)
			(end 0.5 -0.25)
			(stroke
				(width 0.15)
				(type solid)
			)
			(fill no)
			(layer "B.Fab")
		)
		(fp_text user "${REFERENCE}"
			(at -0.95 -3.168 180)
			(layer "B.Fab")
			(effects
				(font
					(size 0.7 0.7)
					(thickness 0.15)
				)
				(justify left bottom mirror)
			)
		)
		(fp_text user "License: Apache-2.0"
			(at -0.95 -5.169 180)
			(layer "B.Fab")
			(effects
				(font
					(size 0.7 0.7)
					(thickness 0.15)
				)
				(justify left bottom mirror)
			)
		)
		(fp_text user "Author: Antmicro"
			(at -0.95 -4.169 180)
			(layer "B.Fab")
			(effects
				(font
					(size 0.7 0.7)
					(thickness 0.15)
				)
				(justify left bottom mirror)
			)
		)
		(pad "1" smd roundrect
			(at -0.48 0)
			(size 0.59 0.64)
			(layers "B.Cu" "B.Mask" "B.Paste")
			(roundrect_rratio 0.25)
			(net 1 "GND")
			(pintype "passive")
		)
		(pad "2" smd roundrect
			(at 0.48 0)
			(size 0.59 0.64)
			(layers "B.Cu" "B.Mask" "B.Paste")
			(roundrect_rratio 0.25)
			(net 626 "USER_IN")
			(pintype "passive")
		)
	)
	(footprint "antmicro-footprints:R_0402_1005Metric"
		(layer "B.Cu")
		(at 252.2 186.349)
		(descr "Resistor SMD 0402")
		(tags "resistor SMD 0402")
		(property "Reference" "R241"
			(at 1 0.551 0)
			(layer "B.SilkS")
			(effects
				(font
					(size 0.7 0.7)
					(thickness 0.15)
				)
				(justify right bottom mirror)
			)
		)
		(property "Value" "R_4k7_0402"
			(at -1.011843 -1.772047 0)
			(layer "B.Fab")
			(effects
				(font
					(size 0.7 0.7)
					(thickness 0.15)
				)
				(justify right bottom mirror)
			)
		)
		(property "Datasheet" "https://www.bourns.com/docs/product-datasheets/cr.pdf"
			(at 0 0 0)
			(layer "F.Fab")
			(hide yes)
			(effects
				(font
					(size 1.27 1.27)
					(thickness 0.15)
				)
			)
		)
		(property "MPN" "CR0402-FX-4701GLF"
			(at 0 0 0)
			(unlocked yes)
			(layer "B.Fab")
			(hide yes)
			(effects
				(font
					(size 1 1)
					(thickness 0.15)
				)
				(justify mirror)
			)
		)
		(property "Manufacturer" "Bourns"
			(at 0 0 0)
			(unlocked yes)
			(layer "B.Fab")
			(hide yes)
			(effects
				(font
					(size 1 1)
					(thickness 0.15)
				)
				(justify mirror)
			)
		)
		(property "License" "Apache-2.0"
			(at 0 0 0)
			(unlocked yes)
			(layer "B.Fab")
			(hide yes)
			(effects
				(font
					(size 1 1)
					(thickness 0.15)
				)
				(justify mirror)
			)
		)
		(property "Author" "Antmicro"
			(at 0 0 0)
			(unlocked yes)
			(layer "B.Fab")
			(hide yes)
			(effects
				(font
					(size 1 1)
					(thickness 0.15)
				)
				(justify mirror)
			)
		)
		(property "Val" "4k7"
			(at 0 0 0)
			(unlocked yes)
			(layer "B.Fab")
			(hide yes)
			(effects
				(font
					(size 1 1)
					(thickness 0.15)
				)
				(justify mirror)
			)
		)
		(property "Tolerance" "1%"
			(at 0 0 0)
			(unlocked yes)
			(layer "B.Fab")
			(hide yes)
			(effects
				(font
					(size 1 1)
					(thickness 0.15)
				)
				(justify mirror)
			)
		)
		(sheetname "/I^{2}C + I3C/")
		(sheetfile "i2c.kicad_sch")
		(attr smd)
		(fp_rect
			(start -0.925 0.47)
			(end 0.925 -0.47)
			(stroke
				(width 0.05)
				(type default)
			)
			(fill no)
			(layer "B.CrtYd")
		)
		(fp_rect
			(start -0.5 0.25)
			(end 0.5 -0.25)
			(stroke
				(width 0.15)
				(type solid)
			)
			(fill no)
			(layer "B.Fab")
		)
		(fp_text user "Author: Antmicro"
			(at -0.95 -4.169 180)
			(layer "B.Fab")
			(effects
				(font
					(size 0.7 0.7)
					(thickness 0.15)
				)
				(justify left bottom mirror)
			)
		)
		(fp_text user "${REFERENCE}"
			(at -0.95 -3.168 180)
			(layer "B.Fab")
			(effects
				(font
					(size 0.7 0.7)
					(thickness 0.15)
				)
				(justify left bottom mirror)
			)
		)
		(fp_text user "License: Apache-2.0"
			(at -0.95 -5.169 180)
			(layer "B.Fab")
			(effects
				(font
					(size 0.7 0.7)
					(thickness 0.15)
				)
				(justify left bottom mirror)
			)
		)
		(pad "1" smd roundrect
			(at -0.48 0)
			(size 0.59 0.64)
			(layers "B.Cu" "B.Mask" "B.Paste")
			(roundrect_rratio 0.25)
			(net 369 "/I^{2}C + I3C/I3C_EXT.SCL")
			(pintype "passive")
		)
		(pad "2" smd roundrect
			(at 0.48 0)
			(size 0.59 0.64)
			(layers "B.Cu" "B.Mask" "B.Paste")
			(roundrect_rratio 0.25)
			(net 782 "Net-(Q24-D)")
			(pintype "passive")
		)
	)
)
